# T6G (Grand Teton) — schematic netlist excerpt (pin names and nets, part order shuffled) for the footprints in the layout excerpt that follows; sources: Cadence DE-HDL packaged netlist, KiCad conversion of 04192023_DAF0TMB3IC0_F0TG_MB_C_brd_V02_OCP.brd

R3352  Q_RES  0 5% CHIP  pkg 0402LF  page 55 : A = CLK_100M_CPU1_CLK11_R_DP ; B = CLK_100M_CPU1_CLK11_DP
R685  Q_RES  33 5% CHIP  pkg 0402LF  page 81 : A = RST_PERST_E1S_0_R_N ; B = RST_PERST_E1S_0_N

(kicad_pcb
	(version 20260206)
	(generator "pcbnew")
	(generator_version "10.0")
	(general
		(thickness 1.6)
		(legacy_teardrops no)
	)
	(paper "A4")
	(title_block
		(title "04192023_DAF0TMB3IC0_F0TG_MB_C_brd_V02_OCP.brd")
		(comment 1 "Grand Teton / footprints 4163-4164 of 8354")
	)
	(layers
		(0 "F.Cu" signal "TOP")
		(4 "In1.Cu" signal "GND")
		(6 "In2.Cu" signal "IN1")
		(8 "In3.Cu" signal "GND1")
		(10 "In4.Cu" signal "IN2")
		(12 "In5.Cu" signal "GND2")
		(14 "In6.Cu" signal "IN3")
		(16 "In7.Cu" signal "GND3")
		(18 "In8.Cu" signal "VCC")
		(20 "In9.Cu" signal "VCC1")
		(22 "In10.Cu" signal "GND4")
		(24 "In11.Cu" signal "IN4")
		(26 "In12.Cu" signal "GND5")
		(28 "In13.Cu" signal "IN5")
		(30 "In14.Cu" signal "GND6")
		(32 "In15.Cu" signal "IN6")
		(34 "In16.Cu" signal "GND7")
		(2 "B.Cu" signal "BOTTOM")
		(9 "F.Adhes" user "F.Adhesive")
		(11 "B.Adhes" user "B.Adhesive")
		(13 "F.Paste" user "Package Geometry/Pastemask Top")
		(15 "B.Paste" user "Package Geometry/Pastemask Bottom")
		(5 "F.SilkS" user "Ref Des/Silkscreen Top")
		(7 "B.SilkS" user "Ref Des/Silkscreen Bottom")
		(1 "F.Mask" user "Board Geometry/Soldermask Top")
		(3 "B.Mask" user "Board Geometry/Soldermask Bottom")
		(17 "Dwgs.User" user "User.Drawings")
		(19 "Cmts.User" user "User.Comments")
		(21 "Eco1.User" user "User.Eco1")
		(23 "Eco2.User" user "User.Eco2")
		(25 "Edge.Cuts" user "Board Geometry/Outline")
		(27 "Margin" user)
		(31 "F.CrtYd" user "Package Geometry/Place Bound Top")
		(29 "B.CrtYd" user "Package Geometry/Place Bound Bottom")
		(35 "F.Fab" user "Ref Des/Assembly Top")
		(33 "B.Fab" user "Ref Des/Assembly Bottom")
	)
	(footprint ""
		(layer "F.Cu")
		(at 197.269608 -117.689376)
		(property "Reference" "R685"
			(at 0 0 0)
			(layer "F.SilkS")
			(hide yes)
			(effects
				(font
					(size 1.27 1.27)
				)
			)
		)
		(property "Value" ""
			(at 0 0 0)
			(layer "F.Fab")
			(effects
				(font
					(size 1.27 1.27)
				)
			)
		)
		(duplicate_pad_numbers_are_jumpers no)
		(fp_line
			(start -0.7874 -0.4064)
			(end 0.7874 -0.4064)
			(stroke
				(width 0.1524)
				(type default)
			)
			(layer "F.SilkS")
		)
		(fp_line
			(start -0.7874 0.4064)
			(end -0.7874 -0.4064)
			(stroke
				(width 0.1524)
				(type default)
			)
			(layer "F.SilkS")
		)
		(fp_line
			(start 0.7874 -0.4064)
			(end 0.7874 0.4064)
			(stroke
				(width 0.1524)
				(type default)
			)
			(layer "F.SilkS")
		)
		(fp_line
			(start 0.7874 0.4064)
			(end -0.7874 0.4064)
			(stroke
				(width 0.1524)
				(type default)
			)
			(layer "F.SilkS")
		)
		(fp_line
			(start -0.67945 -0.305054)
			(end -0.12065 -0.305054)
			(stroke
				(width 0.1)
				(type default)
			)
			(layer "F.Fab")
		)
		(fp_line
			(start -0.67945 0.3048)
			(end -0.67945 -0.305054)
			(stroke
				(width 0.1)
				(type default)
			)
			(layer "F.Fab")
		)
		(fp_line
			(start -0.12065 -0.305054)
			(end -0.12065 -0.2794)
			(stroke
				(width 0.1)
				(type default)
			)
			(layer "F.Fab")
		)
		(fp_line
			(start -0.12065 -0.2794)
			(end 0.12065 -0.2794)
			(stroke
				(width 0.1)
				(type default)
			)
			(layer "F.Fab")
		)
		(fp_line
			(start -0.12065 0.2794)
			(end -0.12065 0.3048)
			(stroke
				(width 0.1)
				(type default)
			)
			(layer "F.Fab")
		)
		(fp_line
			(start -0.12065 0.3048)
			(end -0.67945 0.3048)
			(stroke
				(width 0.1)
				(type default)
			)
			(layer "F.Fab")
		)
		(fp_line
			(start 0.120396 0.2794)
			(end -0.12065 0.2794)
			(stroke
				(width 0.1)
				(type default)
			)
			(layer "F.Fab")
		)
		(fp_line
			(start 0.120396 0.3048)
			(end 0.120396 0.2794)
			(stroke
				(width 0.1)
				(type default)
			)
			(layer "F.Fab")
		)
		(fp_line
			(start 0.12065 -0.3048)
			(end 0.67945 -0.3048)
			(stroke
				(width 0.1)
				(type default)
			)
			(layer "F.Fab")
		)
		(fp_line
			(start 0.12065 -0.2794)
			(end 0.12065 -0.3048)
			(stroke
				(width 0.1)
				(type default)
			)
			(layer "F.Fab")
		)
		(fp_line
			(start 0.67945 -0.3048)
			(end 0.67945 0.3048)
			(stroke
				(width 0.1)
				(type default)
			)
			(layer "F.Fab")
		)
		(fp_line
			(start 0.67945 0.3048)
			(end 0.120396 0.3048)
			(stroke
				(width 0.1)
				(type default)
			)
			(layer "F.Fab")
		)
		(pad "1" smd circle
			(at -0.40005 0)
			(size 0 0)
			(layers "F.Cu" "F.Mask" "F.Paste")
			(net "RST_PERST_E1S_0_R_N")
		)
		(pad "2" smd circle
			(at 0.40005 0)
			(size 0 0)
			(layers "F.Cu" "F.Mask" "F.Paste")
			(net "RST_PERST_E1S_0_N")
		)
	)
	(footprint ""
		(layer "F.Cu")
		(at 126.111 -321.655948 90)
		(property "Reference" "R3352"
			(at 0 0 90)
			(layer "F.SilkS")
			(hide yes)
			(effects
				(font
					(size 1.27 1.27)
				)
			)
		)
		(property "Value" ""
			(at 0 0 90)
			(layer "F.Fab")
			(effects
				(font
					(size 1.27 1.27)
				)
			)
		)
		(duplicate_pad_numbers_are_jumpers no)
		(fp_line
			(start -0.371348 -0.4064)
			(end 0.390652 -0.4064)
			(stroke
				(width 0.1524)
				(type default)
			)
			(layer "F.SilkS")
		)
		(fp_line
			(start 0.7874 0)
			(end 0.7874 0.4064)
			(stroke
				(width 0.1524)
				(type default)
			)
			(layer "F.SilkS")
		)
		(fp_line
			(start 0.7874 0.4064)
			(end -0.7874 0.4064)
			(stroke
				(width 0.1524)
				(type default)
			)
			(layer "F.SilkS")
		)
		(fp_line
			(start -0.7874 0.4064)
			(end -0.7874 0.0254)
			(stroke
				(width 0.1524)
				(type default)
			)
			(layer "F.SilkS")
		)
		(fp_line
			(start -0.12065 -0.305054)
			(end -0.12065 -0.2794)
			(stroke
				(width 0.1)
				(type default)
			)
			(layer "F.Fab")
		)
		(fp_line
			(start -0.67945 -0.305054)
			(end -0.12065 -0.305054)
			(stroke
				(width 0.1)
				(type default)
			)
			(layer "F.Fab")
		)
		(fp_line
			(start 0.67945 -0.3048)
			(end 0.67945 0.3048)
			(stroke
				(width 0.1)
				(type default)
			)
			(layer "F.Fab")
		)
		(fp_line
			(start 0.12065 -0.3048)
			(end 0.67945 -0.3048)
			(stroke
				(width 0.1)
				(type default)
			)
			(layer "F.Fab")
		)
		(fp_line
			(start 0.12065 -0.2794)
			(end 0.12065 -0.3048)
			(stroke
				(width 0.1)
				(type default)
			)
			(layer "F.Fab")
		)
		(fp_line
			(start -0.12065 -0.2794)
			(end 0.12065 -0.2794)
			(stroke
				(width 0.1)
				(type default)
			)
			(layer "F.Fab")
		)
		(fp_line
			(start 0.120396 0.2794)
			(end -0.12065 0.2794)
			(stroke
				(width 0.1)
				(type default)
			)
			(layer "F.Fab")
		)
		(fp_line
			(start -0.12065 0.2794)
			(end -0.12065 0.3048)
			(stroke
				(width 0.1)
				(type default)
			)
			(layer "F.Fab")
		)
		(fp_line
			(start 0.67945 0.3048)
			(end 0.120396 0.3048)
			(stroke
				(width 0.1)
				(type default)
			)
			(layer "F.Fab")
		)
		(fp_line
			(start 0.120396 0.3048)
			(end 0.120396 0.2794)
			(stroke
				(width 0.1)
				(type default)
			)
			(layer "F.Fab")
		)
		(fp_line
			(start -0.12065 0.3048)
			(end -0.67945 0.3048)
			(stroke
				(width 0.1)
				(type default)
			)
			(layer "F.Fab")
		)
		(fp_line
			(start -0.67945 0.3048)
			(end -0.67945 -0.305054)
			(stroke
				(width 0.1)
				(type default)
			)
			(layer "F.Fab")
		)
		(pad "1" smd circle
			(at -0.40005 0 90)
			(size 0 0)
			(layers "F.Cu" "F.Mask" "F.Paste")
			(net "CLK_100M_CPU1_CLK11_R_DP")
		)
		(pad "2" smd circle
			(at 0.40005 0 90)
			(size 0 0)
			(layers "F.Cu" "F.Mask" "F.Paste")
			(net "CLK_100M_CPU1_CLK11_DP")
		)
	)
)
